# S9S_MB_2U (Grand Teton) — schematic parts with pin connectivity, parts 1165–1324 of 6093; source: Cadence DE-HDL packaged netlist (pstxprt.dat, pstxnet.dat, pstchip.dat)

C1869  Q_CAP  0.1UF 25V 10% X7R  pkg 0402  page 167 : 1 = P2E_MB_BMC_RX_BUF_C_DN<0> ; 2 = P2E_MB_BMC_RX_BUF_DN<0>
C1870  Q_CAP  0.1UF 25V 10% X7R  pkg 0402  page 167 : 1 = P2E_MB_BMC_TX_BUF_DP<0> ; 2 = P2E_MB_BMC_TX_BUF_C_DP<0>
C1871  Q_CAP  0.1UF 25V 10% X7R  pkg 0402  page 167 : 1 = P2E_MB_BMC_TX_BUF_DN<0> ; 2 = P2E_MB_BMC_TX_BUF_C_DN<0>
C1873  Q_CAP  0.1UF 25V 10% X7R  pkg 0402  page 190 : 1 = P3V3_AUX ; 2 = GND
C1874  Q_CAP  0.1UF 25V 10% X7R  pkg 0402  page 165 : 1 = P3V3_AUX ; 2 = GND
C1875  Q_CAP  0.1UF 25V 10% X7R  pkg 0402  page 165 : 1 = P3V3_AUX ; 2 = GND
C1876  Q_CAP  0.1UF 25V 10% X7R  pkg 0402  page 165 : 1 = P3V3_AUX ; 2 = GND
C1877  Q_CAP  0.1UF 25V 10% X7R  pkg 0402  page 165 : 1 = P3V3_AUX ; 2 = GND
C1878  Q_CAP  0.1UF 25V 10% X7R  pkg 0402  page 165 : 1 = P3V3_AUX ; 2 = GND
C1879  Q_CAP  0.1UF 25V 10% X7R  pkg 0402  page 165 : 1 = P3V3_AUX ; 2 = GND
C1880  Q_CAP  0.1UF 25V 10% X7R  pkg 0402  page 165 : 1 = P3V3_AUX ; 2 = GND
C1881  Q_CAP  1000PF 50V 5% EMPTY  pkg 0402  page 148 : 1 = GPU_FPGA_READY_ISO ; 2 = GND
C1882  Q_CAP  0.1UF 25V 10% X7R  pkg 0402  page 212 : 1 = P3V3_AUX ; 2 = GND
C1883  Q_CAP  10UF 25V 10% X6S  pkg C0805  page 212 : 1 = VFG3P3_CLK_GEN ; 2 = GND
C1884  Q_CAP  1UF 25V 10% X6S  pkg C0402  page 212 : 1 = VFG_3P3A_CLK_GEN ; 2 = GND
C1886  Q_CAP  0.1UF 25V 10% X7R  pkg 0402  page 212 : 1 = VFG3P3_CLK_GEN ; 2 = GND
C1889  Q_CAP  0.1UF 25V 10% X7R  pkg 0402  page 212 : 1 = VFG3P3_CLK_GEN ; 2 = GND
C1893  Q_CAP  0.01UF 50V 10% X7R  pkg C0402  page 217 : 1 = P3V3_AUX_FPGA_VCCIO4 ; 2 = GND
C1894  Q_CAP  0.01UF 50V 10% X7R  pkg C0402  page 217 : 1 = P3V3_AUX_FPGA_VCCIO2 ; 2 = GND
C1895  Q_CAP  0.01UF 50V 10% X7R  pkg C0402  page 217 : 1 = P3V3_AUX_FPGA_VCCIO0 ; 2 = GND
C1896  Q_CAP  0.01UF 50V 10% X7R  pkg C0402  page 217 : 1 = P3V3_AUX_FPGA_VCCIO1 ; 2 = GND
C1897  Q_CAP  0.01UF 50V 10% X7R  pkg C0402  page 217 : 1 = VCC_PLD_CORE ; 2 = GND
C1898  Q_CAP  0.01UF 50V 10% X7R  pkg C0402  page 217 : 1 = P3V3_AUX_FPGA_VCCIO5 ; 2 = GND
C1899  Q_CAP  0.01UF 50V 10% X7R  pkg C0402  page 217 : 1 = P3V3_AUX_FPGA_VCCIO4 ; 2 = GND
C1900  Q_CAP  0.01UF 50V 10% X7R  pkg C0402  page 217 : 1 = P3V3_AUX_FPGA_VCCIO2 ; 2 = GND
C1901  Q_CAP  0.01UF 50V 10% X7R  pkg C0402  page 217 : 1 = P3V3_AUX_FPGA_VCCIO0 ; 2 = GND
C1902  Q_CAP  0.01UF 50V 10% X7R  pkg C0402  page 217 : 1 = P3V3_AUX_FPGA_VCCIO1 ; 2 = GND
C1903  Q_CAP  0.01UF 50V 10% X7R  pkg C0402  page 217 : 1 = VCC_PLD_CORE ; 2 = GND
C1904  Q_CAP  0.01UF 50V 10% X7R  pkg C0402  page 217 : 1 = P3V3_AUX_FPGA_VCCIO5 ; 2 = GND
C1905  Q_CAP  0.1UF 25V 10% X7R  pkg 0402  page 217 : 1 = P3V3_AUX_FPGA_VCCIO0 ; 2 = GND
C1906  Q_CAP  0.1UF 25V 10% X7R  pkg 0402  page 217 : 1 = P3V3_AUX_FPGA_VCCIO1 ; 2 = GND
C1907  Q_CAP  0.1UF 25V 10% X7R  pkg 0402  page 217 : 1 = VCC_PLD_CORE ; 2 = GND
C1908  Q_CAP  0.01UF 50V 10% X7R  pkg C0402  page 217 : 1 = P3V3_AUX_FPGA_VCCIO4 ; 2 = GND
C1909  Q_CAP  0.01UF 50V 10% X7R  pkg C0402  page 217 : 1 = P3V3_AUX_FPGA_VCCIO2 ; 2 = GND
C1910  Q_CAP  0.01UF 50V 10% X7R  pkg C0402  page 217 : 1 = P3V3_AUX_FPGA_VCCIO0 ; 2 = GND
C1911  Q_CAP  0.01UF 50V 10% X7R  pkg C0402  page 217 : 1 = P3V3_AUX_FPGA_VCCIO1 ; 2 = GND
C1912  Q_CAP  0.01UF 50V 10% X7R  pkg C0402  page 217 : 1 = VCC_PLD_CORE ; 2 = GND
C1913  Q_CAP  0.01UF 50V 10% X7R  pkg C0402  page 217 : 1 = P3V3_AUX_FPGA_VCCIO5 ; 2 = GND
C1914  Q_CAP  0.01UF 50V 10% X7R  pkg C0402  page 217 : 1 = P3V3_AUX_FPGA_VCCIO0 ; 2 = GND
C1915  Q_CAP  0.01UF 50V 10% X7R  pkg C0402  page 217 : 1 = P3V3_AUX_FPGA_VCCIO1 ; 2 = GND
C1916  Q_CAP  0.01UF 50V 10% X7R  pkg C0402  page 217 : 1 = VCC_PLD_CORE ; 2 = GND
C1917  Q_CAP  0.01UF 50V 10% X7R  pkg C0402  page 217 : 1 = P3V3_AUX_FPGA_VCCIO0 ; 2 = GND
C1918  Q_CAP  0.01UF 50V 10% X7R  pkg C0402  page 217 : 1 = P3V3_AUX_FPGA_VCCIO1 ; 2 = GND
C1919  Q_CAP  0.01UF 50V 10% X7R  pkg C0402  page 217 : 1 = VCC_PLD_CORE ; 2 = GND
C1920  Q_CAP  22UF 6.3V 20% X6S  pkg C0603  page 190 : 1 = P3V3_M2_0 ; 2 = GND
C1921  Q_CAP  22UF 6.3V 20% X6S  pkg C0603  page 190 : 1 = P3V3_M2_0 ; 2 = GND
C1922  Q_CAP  22UF 6.3V 20% X6S  pkg C0603  page 190 : 1 = P3V3_M2_0 ; 2 = GND
C1923  Q_CAP  0.1UF 25V 10% X7R  pkg 0402  page 190 : 1 = P3V3_M2_0 ; 2 = GND
C1924  Q_CAP  0.1UF 25V 10% X7R  pkg 0402  page 190 : 1 = P3V3_M2_0 ; 2 = GND
C1925  Q_CAP  0.1UF 25V 10% X7R  pkg 0402  page 190 : 1 = P3V3_M2_0 ; 2 = GND
C1926  Q_CAP  0.01UF 50V 10% X7R  pkg C0402  page 217 : 1 = P3V3_AUX_FPGA_VCCIO0 ; 2 = GND
C1927  Q_CAP  0.01UF 50V 10% X7R  pkg C0402  page 217 : 1 = P3V3_AUX_FPGA_VCCIO1 ; 2 = GND
C1928  Q_CAP  0.01UF 50V 10% X7R  pkg C0402  page 217 : 1 = VCC_PLD_CORE ; 2 = GND
C1929  Q_CAP  0.01UF 50V 10% X7R  pkg C0402  page 217 : 1 = P3V3_AUX_FPGA_VCCIO0 ; 2 = GND
C1930  Q_CAP  0.01UF 50V 10% X7R  pkg C0402  page 217 : 1 = P3V3_AUX_FPGA_VCCIO1 ; 2 = GND
C1931  Q_CAP  0.01UF 50V 10% X7R  pkg C0402  page 217 : 1 = VCC_PLD_CORE ; 2 = GND
C1932  Q_CAP  0.01UF 50V 10% X7R  pkg C0402  page 217 : 1 = P3V3_AUX_FPGA_VCCIO0 ; 2 = GND
C1933  Q_CAP  0.01UF 50V 10% X7R  pkg C0402  page 217 : 1 = P3V3_AUX_FPGA_VCCIO1 ; 2 = GND
C1934  Q_CAP  0.01UF 50V 10% X7R  pkg C0402  page 217 : 1 = VCC_PLD_CORE ; 2 = GND
C1935  Q_CAP  10UF 6.3V 20% X6S  pkg C0402  page 217 : 1 = P3V3_AUX_FPGA_VCCIO4 ; 2 = GND
C1936  Q_CAP  10UF 6.3V 20% X6S  pkg C0402  page 217 : 1 = VCC_PLD_CORE ; 2 = GND
C1937  Q_CAP  10UF 6.3V 20% X6S  pkg C0402  page 217 : 1 = P3V3_AUX_FPGA_VCCIO2 ; 2 = GND
C1938  Q_CAP  10UF 6.3V 20% X6S  pkg C0402  page 217 : 1 = P3V3_AUX_FPGA_VCCIO0 ; 2 = GND
C1939  Q_CAP  10UF 6.3V 20% X6S  pkg C0402  page 217 : 1 = P3V3_AUX_FPGA_VCCIO1 ; 2 = GND
C1940  Q_CAP  10UF 6.3V 20% X6S  pkg C0402  page 217 : 1 = P3V3_AUX_FPGA_VCCIO5 ; 2 = GND
C1941  Q_CAP  0.1UF 25V 10% X7R  pkg 0402  page 217 : 1 = P3V3_AUX_FPGA_VCCIO3 ; 2 = GND
C1942  Q_CAP  0.1UF 25V 10% X7R  pkg 0402  page 217 : 1 = P3V3_AUX_FPGA_VCCIO4 ; 2 = GND
C1943  Q_CAP  0.1UF 25V 10% X7R  pkg 0402  page 217 : 1 = VCC_PLD_CORE ; 2 = GND
C1944  Q_CAP  0.1UF 25V 10% X7R  pkg 0402  page 217 : 1 = P3V3_AUX_FPGA_VCCIO2 ; 2 = GND
C1945  Q_CAP  0.1UF 25V 10% X7R  pkg 0402  page 217 : 1 = P3V3_AUX_FPGA_VCCIO0 ; 2 = GND
C1946  Q_CAP  0.1UF 25V 10% X7R  pkg 0402  page 217 : 1 = P3V3_AUX_FPGA_VCCIO1 ; 2 = GND
C1947  Q_CAP  0.1UF 25V 10% X7R  pkg 0402  page 217 : 1 = P3V3_AUX_FPGA_VCCIO5 ; 2 = GND
C1957  Q_CAP  0.1UF 25V 10% X7R  pkg 0402  page 149 : 1 = P3V3_AUX ; 2 = GND
C1958  Q_CAP  0.1UF 25V 10% X7R  pkg 0402  page 149 : 1 = P3V3_AUX ; 2 = GND
C1963  Q_CAP  0.1UF 25V 10% X7R  pkg 0402  page 150 : 1 = P3V3_AUX ; 2 = GND
C1973  Q_CAP  1000PF 50V 5% EMPTY  pkg 0402  page 147 : 1 = GPU_BASE_HMC_READY_ISO ; 2 = GND
C1974  Q_CAP  1000PF 50V 5% EMPTY  pkg 0402  page 147 : 1 = GPU_FPGA_THERM_OVERT_ISO_N ; 2 = GND
C1975  Q_CAP  1000PF 50V 5% EMPTY  pkg 0402  page 147 : 1 = GPU_HMC_PRSNT_ISO_N ; 2 = GND
C1976  Q_CAP  1000PF 50V 5% EMPTY  pkg 0402  page 147 : 1 = GPU_FPGA_OVERT_ISO_N ; 2 = GND
C1977  Q_CAP  0.1UF 25V 10% X7R  pkg 0402  page 149 : 1 = P3V3_AUX ; 2 = GND
C1978  Q_CAP  1000PF 50V 5% EMPTY  pkg 0402  page 147 : 1 = GPU_PRSNT_N_ISO ; 2 = GND
C1979  Q_CAP  0.1UF 25V 10% X7R  pkg 0402  page 150 : 1 = P3V3_AUX ; 2 = GND
C1988  Q_CAP  1000PF 50V 5% EMPTY  pkg 0402  page 147 : 1 = GPU_FPGA_EROT_FATALERR_ISO_N ; 2 = GND
C1989  Q_CAP_DIFFBUS  DIFF BUS_0.22UF 6.3V 20% X6S  pkg C0201  page 181 : 1 = P3E_PCH_E1S_TX_DP<3> ; 2 = P3E_PCH_E1S_TX_C_DP<3>
C1990  Q_CAP_DIFFBUS  DIFF BUS_0.22UF 6.3V 20% X6S  pkg C0201  page 181 : 1 = P3E_PCH_E1S_TX_DN<3> ; 2 = P3E_PCH_E1S_TX_C_DN<3>
C1991  Q_CAP_DIFFBUS  DIFF BUS_0.22UF 6.3V 20% X6S  pkg C0201  page 181 : 1 = P3E_PCH_E1S_TX_DP<2> ; 2 = P3E_PCH_E1S_TX_C_DP<2>
C1992  Q_CAP_DIFFBUS  DIFF BUS_0.22UF 6.3V 20% X6S  pkg C0201  page 181 : 1 = P3E_PCH_E1S_TX_DN<2> ; 2 = P3E_PCH_E1S_TX_C_DN<2>
C1993  Q_CAP_DIFFBUS  DIFF BUS_0.22UF 6.3V 20% X6S  pkg C0201  page 181 : 1 = P3E_PCH_E1S_TX_DP<1> ; 2 = P3E_PCH_E1S_TX_C_DP<1>
C1994  Q_CAP_DIFFBUS  DIFF BUS_0.22UF 6.3V 20% X6S  pkg C0201  page 181 : 1 = P3E_PCH_E1S_TX_DN<1> ; 2 = P3E_PCH_E1S_TX_C_DN<1>
C1995  Q_CAP_DIFFBUS  DIFF BUS_0.22UF 6.3V 20% X6S  pkg C0201  page 181 : 1 = P3E_PCH_E1S_TX_DP<0> ; 2 = P3E_PCH_E1S_TX_C_DP<0>
C1996  Q_CAP_DIFFBUS  DIFF BUS_0.22UF 6.3V 20% X6S  pkg C0201  page 181 : 1 = P3E_PCH_E1S_TX_DN<0> ; 2 = P3E_PCH_E1S_TX_C_DN<0>
C1997  Q_CAP  0.1UF 25V 10% X7R  pkg 0402  page 194 : 1 = P3V3_AUX ; 2 = GND
C1998  Q_CAP  0.1UF 25V 10% X7R  pkg 0402  page 194 : 1 = P3V3_E1S_0 ; 2 = GND
C2007  Q_CAP  1UF 25V 10% X6S  pkg C0402  page 190 : 1 = P3V3_AUX ; 2 = GND
C2010  Q_CAP  0.1UF 25V 10% X7R  pkg 0402  page 170 : 1 = P3V3_AUX ; 2 = GND
C2012  Q_CAP  0.1UF 25V 10% X7R  pkg 0402  page 172 : 1 = P3V3_AUX ; 2 = GND
C2013  Q_CAP  0.1UF 25V 10% X7R  pkg 0402  page 172 : 1 = P3V3_AUX ; 2 = GND
C2014  Q_CAP  0.1UF 25V 10% X7R  pkg 0402  page 172 : 1 = P3V3_AUX ; 2 = GND
C2015  Q_CAP  0.1UF 25V 10% X7R  pkg 0402  page 171 : 1 = P3V3_AUX ; 2 = GND
C2017  Q_CAP  0.1UF 25V 10% X7R  pkg 0402  page 172 : 1 = P3V3_OCP_V3_2_R ; 2 = GND
C2018  Q_CAP  0.1UF 25V 10% X7R  pkg 0402  page 172 : 1 = P3V3 ; 2 = GND
C2019  Q_CAP  0.1UF 25V 10% X7R  pkg 0402  page 172 : 1 = P12V_SCM_R ; 2 = GND
C2020  Q_CAP  0.1UF 25V 10% X7R  pkg 0402  page 172 : 1 = VSENSE_P12V_INA230_3_INP ; 2 = VSENSE_P12V_INA230_3_INN
C2021  Q_CAP  0.1UF 25V 10% X7R  pkg 0402  page 172 : 1 = VSENSE_P12V_INA230_4_INP ; 2 = VSENSE_P12V_INA230_4_INN
C2022  Q_CAP  0.1UF 25V 10% X7R  pkg 0402  page 172 : 1 = VSENSE_P12V_INA230_5_INP ; 2 = VSENSE_P12V_INA230_5_INN
C2024  Q_CAP  0.1UF 25V 10% X7R  pkg 0402  page 171 : 1 = P3V3_OCP_SFF_R ; 2 = GND
C2027  Q_CAP  0.1UF 25V 10% X7R  pkg 0402  page 171 : 1 = VSENSE_P3V3_INA230_1_INP ; 2 = VSENSE_P3V3_INA230_1_INN
C2029  Q_CAP  18PF 50V 5% C0G  pkg 0402  page 152 : 1 = USB_HUB_XTAL_IN ; 2 = GND
C2030  Q_CAP  18PF 50V 5% C0G  pkg 0402  page 152 : 1 = USB_HUB_XTAL_OUT ; 2 = GND
C2031  Q_CAP  1UF 25V 10% X6S  pkg C0402  page 152 : 1 = P3V3_AUX_USB_HUB ; 2 = GND
C2032  Q_CAP  0.1UF 25V 10% X7R  pkg 0402  page 152 : 1 = P3V3_AUX_USB_HUB ; 2 = GND
C2033  Q_CAP  0.1UF 25V 10% X7R  pkg 0402  page 152 : 1 = P3V3_AUX_USB_HUB ; 2 = GND
C2034  Q_CAP  0.1UF 25V 10% X7R  pkg 0402  page 152 : 1 = P3V3_AUX_USB_HUB ; 2 = GND
C2035  Q_CAP  1UF 25V 10% X6S  pkg C0402  page 152 : 1 = P3V3_AUX_USB_HUB ; 2 = GND
C2036  Q_CAP  8.2PF 50V 0.1P NP0  pkg C0402  page 208 : 1 = XTAL_CLK_GEN1_25M_X1_R ; 2 = GND
C2037  Q_CAP  8.2PF 50V 0.1P NP0  pkg C0402  page 208 : 1 = XTAL_CLK_GEN1_25M_X2 ; 2 = GND
C2038  Q_CAP  10UF 6.3V 20% X6S  pkg C0402  page 152 : 1 = P3V3_AUX_USB_HUB ; 2 = GND
C2039  Q_CAP  0.1UF 25V 10% X7R  pkg 0402  page 152 : 1 = P3V3_AUX_USB_HUB ; 2 = GND
C2040  Q_CAP  0.1UF 25V 10% X7R  pkg 0402  page 152 : 1 = P3V3_AUX_USB_HUB ; 2 = GND
C2041  Q_CAP  1UF 25V 10% X6S  pkg C0402  page 152 : 1 = RST_USB_HUB_R_N ; 2 = GND
C2042  Q_CAP  100PF 50V 5% EMPTY  pkg 0402  page 250 : 1 = P3V3_AUX_ADC_MAM ; 2 = GND
C2043  Q_CAP  100PF 50V 5% EMPTY  pkg 0402  page 250 : 1 = P3V3_ADC_MAM ; 2 = GND
C2044  Q_CAP  100PF 50V 5% EMPTY  pkg 0402  page 250 : 1 = P5V_ADC_MAM ; 2 = GND
C2045  Q_CAP  100PF 50V 5% EMPTY  pkg 0402  page 250 : 1 = P3V3_PDB_AUX_ADC_MAM ; 2 = GND
C2046  Q_CAP  0.1UF 25V 10% X7R  pkg 0402  page 250 : 1 = P12V_AUX_ADC_TIC ; 2 = GND
C2047  Q_CAP  0.1UF 25V 10% X7R  pkg 0402  page 250 : 1 = P3V3_AUX_ADC_TIC ; 2 = GND
C2048  Q_CAP  0.1UF 25V 10% X7R  pkg 0402  page 250 : 1 = P3V3_ADC_TIC ; 2 = GND
C2049  Q_CAP  0.1UF 25V 10% X7R  pkg 0402  page 250 : 1 = P5V_ADC_TIC ; 2 = GND
C2050  Q_CAP  0.1UF 25V 10% X7R  pkg 0402  page 250 : 1 = P3V3_PDB_AUX_ADC_TIC ; 2 = GND
C2051  Q_CAP  0.1UF 25V 10% X7R  pkg 0402  page 250 : 1 = P3V3_ADC128_VCC ; 2 = GND
C2052  Q_CAP  0.1UF 25V 10% X7R  pkg 0402  page 250 : 1 = P3V3_ADC128_VCC ; 2 = GND
C2056  Q_CAP  0.1UF 25V 10% X7R  pkg 0402  page 233 : 1 = P3V3_AUX ; 2 = GND
C2067  Q_CAP  0.1UF 25V 10% X7R  pkg 0402  page 171 : 1 = P3V3_AUX ; 2 = GND
C2069  Q_CAP  0.1UF 25V 10% X7R  pkg 0402  page 171 : 1 = P3V3_E1S_0_R ; 2 = GND
C2071  Q_CAP  0.1UF 25V 10% X7R  pkg 0402  page 171 : 1 = VSENSE_P3V3_INA230_2_INP ; 2 = VSENSE_P3V3_INA230_2_INN
C2073  Q_CAP_DIFFBUS  DIFF BUS_0.22UF 6.3V 20% X6S  pkg C0201  page 181 : 1 = P3E_PCH_NVS_TX_DP<1> ; 2 = P3E_PCH_NVS_TX_C_DP<1>
C2074  Q_CAP_DIFFBUS  DIFF BUS_0.22UF 6.3V 20% X6S  pkg C0201  page 181 : 1 = P3E_PCH_NVS_TX_DN<1> ; 2 = P3E_PCH_NVS_TX_C_DN<1>
C2075  Q_CAP_DIFFBUS  DIFF BUS_0.22UF 6.3V 20% X6S  pkg C0201  page 181 : 1 = P3E_PCH_NVS_TX_DP<0> ; 2 = P3E_PCH_NVS_TX_C_DP<0>
C2076  Q_CAP_DIFFBUS  DIFF BUS_0.22UF 6.3V 20% X6S  pkg C0201  page 181 : 1 = P3E_PCH_NVS_TX_DN<0> ; 2 = P3E_PCH_NVS_TX_C_DN<0>
C2077  Q_CAP_DIFFBUS  DIFF BUS_0.22UF 6.3V 20% X6S  pkg C0201  page 181 : 1 = P3E_PCH_BMC_TX_DP ; 2 = P3E_PCH_BMC_TX_C_DP
C2078  Q_CAP_DIFFBUS  DIFF BUS_0.22UF 6.3V 20% X6S  pkg C0201  page 181 : 1 = P3E_PCH_BMC_TX_DN ; 2 = P3E_PCH_BMC_TX_C_DN
C2148  Q_CAP  0.01UF 50V 10% EMPTY  pkg C0402  page 162 : 1 = P12V_OCP_V3_2 ; 2 = P12V_OCP_GATE_2
C2175  Q_CAP  100PF 50V 5% EMPTY  pkg 0402  page 250 : 1 = P12V_OCP_V3_2_ISENSE_MAM ; 2 = GND
C2176  Q_CAP  100PF 50V 5% EMPTY  pkg 0402  page 250 : 1 = P12V_OCP_SFF_ISENSE_MAM ; 2 = GND
C2177  Q_CAP  0.1UF 25V 10% X7R  pkg 0402  page 250 : 1 = P12V_OCP_V3_2_ISENSE_TIC ; 2 = GND
C2178  Q_CAP  0.1UF 25V 10% X7R  pkg 0402  page 250 : 1 = P12V_OCP_SFF_ISENSE_TIC ; 2 = GND
C2179  Q_CAP  100NF 50V 10% X7R  pkg C0402  page 301 : 1 = HSC_EN ; 2 = AGND_HSC
C2194  Q_CAP  0.1UF 25V 10% X7R  pkg 0402  page 250 : 1 = P12V_E1S_0_ISENSE_TIC ; 2 = GND
C2195  Q_CAP  100PF 50V 5% EMPTY  pkg 0402  page 250 : 1 = P12V_E1S_0_ISENSE_MAM ; 2 = GND
C2243  Q_CAP  1UF 25V 10% X6S  pkg C0402  page 226 : 1 = P3V3 ; 2 = GND
C2246  Q_CAP  1UF 25V 10% X6S  pkg C0402  page 225 : 1 = P3V3_AUX ; 2 = GND
C2247  Q_CAP  1UF 25V 10% X6S  pkg C0402  page 225 : 1 = P3V3_AUX ; 2 = GND
C2248  Q_CAP  1UF 25V 10% X6S  pkg C0402  page 225 : 1 = P3V3 ; 2 = GND
C2249  Q_CAP  0.1UF 25V 10% X7R  pkg 0402  page 226 : 1 = P0V62_CPU0_ERRS_VREF ; 2 = GND
C2252  Q_CAP  0.1UF 25V 10% X7R  pkg 0402  page 225 : 1 = P0V62_CPU0_RST_DDR_VREF ; 2 = GND
C2253  Q_CAP  0.1UF 25V 10% X7R  pkg 0402  page 225 : 1 = P0V62_CPU1_RST_DDR_VREF ; 2 = GND
C2254  Q_CAP  0.1UF 25V 10% X7R  pkg 0402  page 225 : 1 = P0V62_CPU0_ERRS_U306_VREF ; 2 = GND
C2255  Q_CAP  8.2PF 50V 0.1P NP0  pkg C0402  page 212 : 1 = CLK_GEN2_XTAL_IN_R ; 2 = GND
C2256  Q_CAP  8.2PF 50V 0.1P NP0  pkg C0402  page 212 : 1 = CLK_GEN2_XTAL_OUT ; 2 = GND
C2257  Q_CAP  0.1UF 25V 10% X7R  pkg 0402  page 212 : 1 = VFG3P3_CLK_GEN ; 2 = GND
